FILE_TYPE = CONNECTIVITY;
{Allegro Design Entry HDL 17.4-2019 S026 (4007227) 1/17/2022}
"PAGE_NUMBER" = 1;
0"NC";
END.
